# T6G (Grand Teton) — schematic netlist excerpt (pin names and nets, part order shuffled) for the footprints in the layout excerpt that follows; sources: Cadence DE-HDL packaged netlist, KiCad conversion of 04192023_DAF0TMB3IC0_F0TG_MB_C_brd_V02_OCP.brd

PR2523  Q_RES  1 1% CHIP  pkg 0402LF  page 266 : A = P12V_HSC_SENSE2_P ; B = P12V_HSC_SENSE2_R4_P
C1025  Q_CAP  100UF 4V 20% X6S  pkg C0805  page 312 : A = P0V9_CPU0_RT3_2A ; B = GND
PC395_1  Q_CAP  22UF 4V 20% X6S  pkg C0805  page 218 : A = PVDDCR_CPU1_P1 ; B = GND

(kicad_pcb
	(version 20260206)
	(generator "pcbnew")
	(generator_version "10.0")
	(general
		(thickness 1.6)
		(legacy_teardrops no)
	)
	(paper "A4")
	(title_block
		(title "04192023_DAF0TMB3IC0_F0TG_MB_C_brd_V02_OCP.brd")
		(comment 1 "Grand Teton / footprints 6505-6507 of 8354")
	)
	(layers
		(0 "F.Cu" signal "TOP")
		(4 "In1.Cu" signal "GND")
		(6 "In2.Cu" signal "IN1")
		(8 "In3.Cu" signal "GND1")
		(10 "In4.Cu" signal "IN2")
		(12 "In5.Cu" signal "GND2")
		(14 "In6.Cu" signal "IN3")
		(16 "In7.Cu" signal "GND3")
		(18 "In8.Cu" signal "VCC")
		(20 "In9.Cu" signal "VCC1")
		(22 "In10.Cu" signal "GND4")
		(24 "In11.Cu" signal "IN4")
		(26 "In12.Cu" signal "GND5")
		(28 "In13.Cu" signal "IN5")
		(30 "In14.Cu" signal "GND6")
		(32 "In15.Cu" signal "IN6")
		(34 "In16.Cu" signal "GND7")
		(2 "B.Cu" signal "BOTTOM")
		(9 "F.Adhes" user "F.Adhesive")
		(11 "B.Adhes" user "B.Adhesive")
		(13 "F.Paste" user "Package Geometry/Pastemask Top")
		(15 "B.Paste" user "Package Geometry/Pastemask Bottom")
		(5 "F.SilkS" user "Ref Des/Silkscreen Top")
		(7 "B.SilkS" user "Ref Des/Silkscreen Bottom")
		(1 "F.Mask" user "Board Geometry/Soldermask Top")
		(3 "B.Mask" user "Board Geometry/Soldermask Bottom")
		(17 "Dwgs.User" user "User.Drawings")
		(19 "Cmts.User" user "User.Comments")
		(21 "Eco1.User" user "User.Eco1")
		(23 "Eco2.User" user "User.Eco2")
		(25 "Edge.Cuts" user "Board Geometry/Outline")
		(27 "Margin" user)
		(31 "F.CrtYd" user "Package Geometry/Place Bound Top")
		(29 "B.CrtYd" user "Package Geometry/Place Bound Bottom")
		(35 "F.Fab" user "Ref Des/Assembly Top")
		(33 "B.Fab" user "Ref Des/Assembly Bottom")
	)
	(footprint ""
		(layer "B.Cu")
		(at 74.478134 -326.232012 -90)
		(property "Reference" "PC395_1"
			(at 0 0 90)
			(layer "B.SilkS")
			(hide yes)
			(effects
				(font
					(size 1.27 1.27)
				)
				(justify mirror)
			)
		)
		(property "Value" ""
			(at 0 0 90)
			(layer "B.Fab")
			(effects
				(font
					(size 1.27 1.27)
				)
				(justify mirror)
			)
		)
		(duplicate_pad_numbers_are_jumpers no)
		(fp_line
			(start -1.524 0.762)
			(end 1.524 0.762)
			(stroke
				(width 0.1524)
				(type default)
			)
			(layer "B.SilkS")
		)
		(fp_line
			(start 1.524 0.762)
			(end 1.524 -0.762)
			(stroke
				(width 0.1524)
				(type default)
			)
			(layer "B.SilkS")
		)
		(fp_line
			(start -1.524 -0.762)
			(end -1.524 0.762)
			(stroke
				(width 0.1524)
				(type default)
			)
			(layer "B.SilkS")
		)
		(fp_line
			(start 1.524 -0.762)
			(end -1.524 -0.762)
			(stroke
				(width 0.1524)
				(type default)
			)
			(layer "B.SilkS")
		)
		(fp_line
			(start -1.1049 0.724916)
			(end -1.1049 -0.724916)
			(stroke
				(width 0.1)
				(type default)
			)
			(layer "B.Fab")
		)
		(fp_line
			(start 1.1049 0.724916)
			(end -1.1049 0.724916)
			(stroke
				(width 0.1)
				(type default)
			)
			(layer "B.Fab")
		)
		(fp_line
			(start -1.1049 -0.724916)
			(end 1.1049 -0.724916)
			(stroke
				(width 0.1)
				(type default)
			)
			(layer "B.Fab")
		)
		(fp_line
			(start 1.1049 -0.724916)
			(end 1.1049 0.724916)
			(stroke
				(width 0.1)
				(type default)
			)
			(layer "B.Fab")
		)
		(pad "1" smd rect
			(at 0.889 0 270)
			(size 1.016 1.27)
			(layers "B.Cu" "B.Mask" "B.Paste")
			(net "PVDDCR_CPU1_P1")
		)
		(pad "2" smd rect
			(at -0.889 0 270)
			(size 1.016 1.27)
			(layers "B.Cu" "B.Mask" "B.Paste")
			(net "GND")
		)
	)
	(footprint ""
		(layer "B.Cu")
		(at 392.961622 -400.19605 180)
		(property "Reference" "C1025"
			(at 0 0 0)
			(layer "B.SilkS")
			(hide yes)
			(effects
				(font
					(size 1.27 1.27)
				)
				(justify mirror)
			)
		)
		(property "Value" ""
			(at 0 0 0)
			(layer "B.Fab")
			(effects
				(font
					(size 1.27 1.27)
				)
				(justify mirror)
			)
		)
		(duplicate_pad_numbers_are_jumpers no)
		(fp_line
			(start 1.524 0.762)
			(end 1.524 -0.762)
			(stroke
				(width 0.1524)
				(type default)
			)
			(layer "B.SilkS")
		)
		(fp_line
			(start 1.524 -0.762)
			(end -1.524 -0.762)
			(stroke
				(width 0.1524)
				(type default)
			)
			(layer "B.SilkS")
		)
		(fp_line
			(start -1.524 0.762)
			(end 1.524 0.762)
			(stroke
				(width 0.1524)
				(type default)
			)
			(layer "B.SilkS")
		)
		(fp_line
			(start -1.524 -0.762)
			(end -1.524 0.762)
			(stroke
				(width 0.1524)
				(type default)
			)
			(layer "B.SilkS")
		)
		(fp_line
			(start 1.1049 0.724916)
			(end -1.1049 0.724916)
			(stroke
				(width 0.1)
				(type default)
			)
			(layer "B.Fab")
		)
		(fp_line
			(start 1.1049 -0.724916)
			(end 1.1049 0.724916)
			(stroke
				(width 0.1)
				(type default)
			)
			(layer "B.Fab")
		)
		(fp_line
			(start -1.1049 0.724916)
			(end -1.1049 -0.724916)
			(stroke
				(width 0.1)
				(type default)
			)
			(layer "B.Fab")
		)
		(fp_line
			(start -1.1049 -0.724916)
			(end 1.1049 -0.724916)
			(stroke
				(width 0.1)
				(type default)
			)
			(layer "B.Fab")
		)
		(pad "1" smd rect
			(at 0.889 0 180)
			(size 1.016 1.27)
			(layers "B.Cu" "B.Mask" "B.Paste")
			(net "P0V9_CPU0_RT3_2A")
		)
		(pad "2" smd rect
			(at -0.889 0 180)
			(size 1.016 1.27)
			(layers "B.Cu" "B.Mask" "B.Paste")
			(net "GND")
		)
	)
	(footprint ""
		(layer "B.Cu")
		(at 206.429356 -382.596136 180)
		(property "Reference" "PR2523"
			(at 0 0 0)
			(layer "B.SilkS")
			(hide yes)
			(effects
				(font
					(size 1.27 1.27)
				)
				(justify mirror)
			)
		)
		(property "Value" ""
			(at 0 0 0)
			(layer "B.Fab")
			(effects
				(font
					(size 1.27 1.27)
				)
				(justify mirror)
			)
		)
		(duplicate_pad_numbers_are_jumpers no)
		(fp_line
			(start 0.7874 0.4064)
			(end 0.7874 -0.4064)
			(stroke
				(width 0.1524)
				(type default)
			)
			(layer "B.SilkS")
		)
		(fp_line
			(start 0.7874 -0.4064)
			(end -0.7874 -0.4064)
			(stroke
				(width 0.1524)
				(type default)
			)
			(layer "B.SilkS")
		)
		(fp_line
			(start -0.7874 0.4064)
			(end 0.7874 0.4064)
			(stroke
				(width 0.1524)
				(type default)
			)
			(layer "B.SilkS")
		)
		(fp_line
			(start -0.7874 -0.4064)
			(end -0.7874 0.4064)
			(stroke
				(width 0.1524)
				(type default)
			)
			(layer "B.SilkS")
		)
		(fp_line
			(start 0.67945 0.3048)
			(end 0.67945 -0.305054)
			(stroke
				(width 0.1)
				(type default)
			)
			(layer "B.Fab")
		)
		(fp_line
			(start 0.67945 -0.305054)
			(end 0.12065 -0.305054)
			(stroke
				(width 0.1)
				(type default)
			)
			(layer "B.Fab")
		)
		(fp_line
			(start 0.12065 0.3048)
			(end 0.67945 0.3048)
			(stroke
				(width 0.1)
				(type default)
			)
			(layer "B.Fab")
		)
		(fp_line
			(start 0.12065 0.2794)
			(end 0.12065 0.3048)
			(stroke
				(width 0.1)
				(type default)
			)
			(layer "B.Fab")
		)
		(fp_line
			(start 0.12065 -0.2794)
			(end -0.12065 -0.2794)
			(stroke
				(width 0.1)
				(type default)
			)
			(layer "B.Fab")
		)
		(fp_line
			(start 0.12065 -0.305054)
			(end 0.12065 -0.2794)
			(stroke
				(width 0.1)
				(type default)
			)
			(layer "B.Fab")
		)
		(fp_line
			(start -0.120396 0.3048)
			(end -0.120396 0.2794)
			(stroke
				(width 0.1)
				(type default)
			)
			(layer "B.Fab")
		)
		(fp_line
			(start -0.120396 0.2794)
			(end 0.12065 0.2794)
			(stroke
				(width 0.1)
				(type default)
			)
			(layer "B.Fab")
		)
		(fp_line
			(start -0.12065 -0.2794)
			(end -0.12065 -0.3048)
			(stroke
				(width 0.1)
				(type default)
			)
			(layer "B.Fab")
		)
		(fp_line
			(start -0.12065 -0.3048)
			(end -0.67945 -0.3048)
			(stroke
				(width 0.1)
				(type default)
			)
			(layer "B.Fab")
		)
		(fp_line
			(start -0.67945 0.3048)
			(end -0.120396 0.3048)
			(stroke
				(width 0.1)
				(type default)
			)
			(layer "B.Fab")
		)
		(fp_line
			(start -0.67945 -0.3048)
			(end -0.67945 0.3048)
			(stroke
				(width 0.1)
				(type default)
			)
			(layer "B.Fab")
		)
		(pad "1" smd circle
			(at 0.40005 0)
			(size 0 0)
			(layers "B.Cu" "B.Mask" "B.Paste")
			(net "P12V_HSC_SENSE2_P")
		)
		(pad "2" smd circle
			(at -0.40005 0)
			(size 0 0)
			(layers "B.Cu" "B.Mask" "B.Paste")
			(net "P12V_HSC_SENSE2_R4_P")
		)
	)
)
